(kicad_pcb
	(version 20260206)
	(generator "pcbnew")
	(generator_version "10.0")
	(general
		(thickness 1.6)
		(legacy_teardrops no)
	)
	(paper "A4")
	(title_block
		(title "v1-chassis-manager — T6M_CM_d_v01_1031_1645.brd")
		(comment 1 "Open CloudServer (Microsoft) / footprints 450-456 of 2512")
	)
	(layers
		(0 "F.Cu" signal "TOP")
		(4 "In1.Cu" signal "GND1")
		(6 "In2.Cu" signal "IN1")
		(8 "In3.Cu" signal "VCC1")
		(10 "In4.Cu" signal "VCC2")
		(12 "In5.Cu" signal "GND2")
		(14 "In6.Cu" signal "IN2")
		(16 "In7.Cu" signal "IN3")
		(18 "In8.Cu" signal "GND3")
		(2 "B.Cu" signal "BOTTOM")
		(9 "F.Adhes" user "F.Adhesive")
		(11 "B.Adhes" user "B.Adhesive")
		(13 "F.Paste" user "Package Geometry/Pastemask Top")
		(15 "B.Paste" user "Package Geometry/Pastemask Bottom")
		(5 "F.SilkS" user "Ref Des/Silkscreen Top")
		(7 "B.SilkS" user "Ref Des/Silkscreen Bottom")
		(1 "F.Mask" user "Board Geometry/Soldermask Top")
		(3 "B.Mask" user "Board Geometry/Soldermask Bottom")
		(17 "Dwgs.User" user "User.Drawings")
		(19 "Cmts.User" user "User.Comments")
		(21 "Eco1.User" user "User.Eco1")
		(23 "Eco2.User" user "User.Eco2")
		(25 "Edge.Cuts" user "Board Geometry/Outline")
		(27 "Margin" user)
		(31 "F.CrtYd" user "Package Geometry/Place Bound Top")
		(29 "B.CrtYd" user "Package Geometry/Place Bound Bottom")
		(35 "F.Fab" user "Ref Des/Assembly Top")
		(33 "B.Fab" user "Ref Des/Assembly Bottom")
	)
	(footprint ""
		(layer "F.Cu")
		(at 15.247366 -60.31357 90)
		(property "Reference" "R637"
			(at -1.68656 -0.98552 90)
			(unlocked yes)
			(layer "F.SilkS")
			(effects
				(font
					(size 0.7874 0.5842)
					(thickness 0.1524)
				)
				(justify left)
			)
		)
		(property "Value" ""
			(at 0 0 90)
			(layer "F.Fab")
			(effects
				(font
					(size 1.27 1.27)
				)
			)
		)
		(duplicate_pad_numbers_are_jumpers no)
		(fp_line
			(start 0.7874 -0.4064)
			(end 0.7874 0.4064)
			(stroke
				(width 0.1524)
				(type default)
			)
			(layer "F.SilkS")
		)
		(fp_line
			(start -0.7874 -0.4064)
			(end 0.7874 -0.4064)
			(stroke
				(width 0.1524)
				(type default)
			)
			(layer "F.SilkS")
		)
		(fp_line
			(start 0.7874 0.4064)
			(end -0.7874 0.4064)
			(stroke
				(width 0.1524)
				(type default)
			)
			(layer "F.SilkS")
		)
		(fp_line
			(start -0.7874 0.4064)
			(end -0.7874 -0.4064)
			(stroke
				(width 0.1524)
				(type default)
			)
			(layer "F.SilkS")
		)
		(fp_poly
			(pts
				(xy -0.508 0.2794) (xy -0.508 0.2286) (xy -0.635 0.2286) (xy -0.635 -0.254) (xy -0.5334 -0.254)
				(xy -0.5334 -0.2794) (xy 0.5334 -0.2794) (xy 0.5334 -0.254) (xy 0.635 -0.254) (xy 0.635 0.254) (xy 0.5334 0.254)
				(xy 0.5334 0.2794)
			)
			(stroke
				(width 0)
				(type default)
			)
			(fill no)
			(layer "F.CrtYd")
		)
		(pad "1" smd rect
			(at 0.40005 0 90)
			(size 0.4572 0.508)
			(layers "F.Cu" "F.Mask" "F.Paste")
			(net "VGA_VSYNC")
		)
		(pad "2" smd rect
			(at -0.40005 0 90)
			(size 0.4572 0.508)
			(layers "F.Cu" "F.Mask" "F.Paste")
			(net "CRT_VSYNC")
		)
	)
	(footprint ""
		(layer "F.Cu")
		(at 105.000044 -95.79991)
		(property "Reference" "H5"
			(at 7.311136 -4.605782 0)
			(unlocked yes)
			(layer "F.SilkS")
			(effects
				(font
					(size 0.7874 0.5842)
					(thickness 0.1524)
				)
				(justify left)
			)
		)
		(property "Value" ""
			(at 0 0 0)
			(layer "F.Fab")
			(effects
				(font
					(size 1.27 1.27)
				)
			)
		)
		(duplicate_pad_numbers_are_jumpers no)
		(fp_circle
			(center 0 0)
			(end 7.999984 0)
			(stroke
				(width 0.1524)
				(type default)
			)
			(fill no)
			(layer "F.SilkS")
		)
		(fp_arc
			(start 11.071352 -9.680448)
			(mid 13.767871 -5.170265)
			(end 14.7066 0)
			(stroke
				(width 0.1524)
				(type default)
			)
			(layer "B.SilkS")
		)
		(fp_arc
			(start 14.7066 0)
			(mid -7.269888 12.784085)
			(end -7.519162 -12.63904)
			(stroke
				(width 0.1524)
				(type default)
			)
			(layer "B.SilkS")
		)
		(fp_circle
			(center 0 0)
			(end 7.999984 0)
			(stroke
				(width 0.1524)
				(type default)
			)
			(fill no)
			(layer "B.SilkS")
		)
		(fp_poly
			(pts
				(arc
					(start 0 5.0038)
					(mid 0 -5.0038)
					(end 0 5.0038)
				)
			)
			(stroke
				(width 0)
				(type default)
			)
			(fill no)
			(layer "F.CrtYd")
		)
		(pad "" np_thru_hole circle
			(at 0 0)
			(size 4.0132 4.0132)
			(drill 4.0132)
			(layers "*.Cu" "*.Mask")
			(clearance 0.381)
			(thermal_gap 0.381)
		)
		(pad "2" thru_hole circle
			(at 0 -3.50012)
			(size 0.762 0.762)
			(drill 0.5588)
			(layers "*.Cu" "*.Mask")
			(remove_unused_layers no)
			(net "GND")
			(clearance 0.1524)
			(thermal_gap 0.1524)
		)
		(pad "3" thru_hole circle
			(at -2.500122 -2.500122)
			(size 0.762 0.762)
			(drill 0.5588)
			(layers "*.Cu" "*.Mask")
			(remove_unused_layers no)
			(net "GND")
			(clearance 0.1524)
			(thermal_gap 0.1524)
		)
		(pad "4" thru_hole circle
			(at -3.50012 0)
			(size 0.762 0.762)
			(drill 0.5588)
			(layers "*.Cu" "*.Mask")
			(remove_unused_layers no)
			(net "GND")
			(clearance 0.1524)
			(thermal_gap 0.1524)
		)
		(pad "5" thru_hole circle
			(at -2.500122 2.500122)
			(size 0.762 0.762)
			(drill 0.5588)
			(layers "*.Cu" "*.Mask")
			(remove_unused_layers no)
			(net "GND")
			(clearance 0.1524)
			(thermal_gap 0.1524)
		)
		(pad "6" thru_hole circle
			(at 0 3.50012)
			(size 0.762 0.762)
			(drill 0.5588)
			(layers "*.Cu" "*.Mask")
			(remove_unused_layers no)
			(net "GND")
			(clearance 0.1524)
			(thermal_gap 0.1524)
		)
		(pad "7" thru_hole circle
			(at 2.500122 2.500122)
			(size 0.762 0.762)
			(drill 0.5588)
			(layers "*.Cu" "*.Mask")
			(remove_unused_layers no)
			(net "GND")
			(clearance 0.1524)
			(thermal_gap 0.1524)
		)
		(pad "8" thru_hole circle
			(at 3.50012 0)
			(size 0.762 0.762)
			(drill 0.5588)
			(layers "*.Cu" "*.Mask")
			(remove_unused_layers no)
			(net "GND")
			(clearance 0.1524)
			(thermal_gap 0.1524)
		)
		(pad "9" thru_hole circle
			(at 2.500122 -2.500122)
			(size 0.762 0.762)
			(drill 0.5588)
			(layers "*.Cu" "*.Mask")
			(remove_unused_layers no)
			(net "GND")
			(clearance 0.1524)
			(thermal_gap 0.1524)
		)
		(zone
			(layer "F.Cu")
			(hatch none 0.5)
			(connect_pads
				(clearance 0)
			)
			(min_thickness 0.25)
			(keepout
				(tracks not_allowed)
				(vias allowed)
				(pads allowed)
				(copperpour not_allowed)
				(footprints allowed)
			)
			(placement
				(enabled no)
				(sheetname "")
			)
			(fill
				(thermal_gap 0.5)
				(thermal_bridge_width 0.5)
				(island_removal_mode 0)
			)
			(polygon
				(pts
					(arc
						(start 105.000044 -90.69451)
						(mid 99.894644 -95.79991)
						(end 105.000044 -100.90531)
					)
					(arc
						(start 105.000044 -103.799894)
						(mid 97.00006 -95.79991)
						(end 105.000044 -87.799926)
					)
				)
			)
		)
		(zone
			(layer "F.Cu")
			(hatch none 0.5)
			(connect_pads
				(clearance 0)
			)
			(min_thickness 0.25)
			(keepout
				(tracks not_allowed)
				(vias allowed)
				(pads allowed)
				(copperpour not_allowed)
				(footprints allowed)
			)
			(placement
				(enabled no)
				(sheetname "")
			)
			(fill
				(thermal_gap 0.5)
				(thermal_bridge_width 0.5)
				(island_removal_mode 0)
			)
			(polygon
				(pts
					(arc
						(start 105.000044 -90.69451)
						(mid 110.105444 -95.79991)
						(end 105.000044 -100.90531)
					)
					(arc
						(start 105.000044 -103.799894)
						(mid 113.000028 -95.79991)
						(end 105.000044 -87.799926)
					)
				)
			)
		)
		(zone
			(layers "F.Cu" "B.Cu" "In1.Cu" "In2.Cu" "In3.Cu" "In4.Cu" "In5.Cu" "In6.Cu"
				"In7.Cu" "In8.Cu"
			)
			(hatch none 0.5)
			(connect_pads
				(clearance 0)
			)
			(min_thickness 0.25)
			(keepout
				(tracks not_allowed)
				(vias allowed)
				(pads allowed)
				(copperpour not_allowed)
				(footprints allowed)
			)
			(placement
				(enabled no)
				(sheetname "")
			)
			(fill
				(thermal_gap 0.5)
				(thermal_bridge_width 0.5)
				(island_removal_mode 0)
			)
			(polygon
				(pts
					(arc
						(start 105.000044 -93.28785)
						(mid 105.000044 -98.31197)
						(end 105.000044 -93.28785)
					)
				)
			)
		)
		(zone
			(layer "B.Cu")
			(hatch none 0.5)
			(connect_pads
				(clearance 0)
			)
			(min_thickness 0.25)
			(keepout
				(tracks not_allowed)
				(vias allowed)
				(pads allowed)
				(copperpour not_allowed)
				(footprints allowed)
			)
			(placement
				(enabled no)
				(sheetname "")
			)
			(fill
				(thermal_gap 0.5)
				(thermal_bridge_width 0.5)
				(island_removal_mode 0)
			)
			(polygon
				(pts
					(xy 99.974654 -90.79611) (xy 99.974654 -95.79991) (xy 99.492054 -95.79991) (xy 99.492054 -90.79611)
				)
			)
		)
		(zone
			(layer "B.Cu")
			(hatch none 0.5)
			(connect_pads
				(clearance 0)
			)
			(min_thickness 0.25)
			(keepout
				(tracks not_allowed)
				(vias allowed)
				(pads allowed)
				(copperpour not_allowed)
				(footprints allowed)
			)
			(placement
				(enabled no)
				(sheetname "")
			)
			(fill
				(thermal_gap 0.5)
				(thermal_bridge_width 0.5)
				(island_removal_mode 0)
			)
			(polygon
				(pts
					(xy 110.025434 -95.79991) (xy 110.025434 -90.79611) (xy 110.508034 -90.79611) (xy 110.508034 -95.79991)
				)
			)
		)
		(zone
			(layer "B.Cu")
			(hatch none 0.5)
			(connect_pads
				(clearance 0)
			)
			(min_thickness 0.25)
			(keepout
				(tracks not_allowed)
				(vias allowed)
				(pads allowed)
				(copperpour not_allowed)
				(footprints allowed)
			)
			(placement
				(enabled no)
				(sheetname "")
			)
			(fill
				(thermal_gap 0.5)
				(thermal_bridge_width 0.5)
				(island_removal_mode 0)
			)
			(polygon
				(pts
					(arc
						(start 110.025434 -95.79991)
						(mid 105.000044 -100.8253)
						(end 99.974654 -95.79991)
					)
					(arc
						(start 99.492054 -95.79991)
						(mid 105.000044 -101.3079)
						(end 110.508034 -95.79991)
					)
				)
			)
		)
		(zone
			(layer "B.Cu")
			(hatch none 0.5)
			(connect_pads
				(clearance 0)
			)
			(min_thickness 0.25)
			(keepout
				(tracks not_allowed)
				(vias allowed)
				(pads allowed)
				(copperpour not_allowed)
				(footprints allowed)
			)
			(placement
				(enabled no)
				(sheetname "")
			)
			(fill
				(thermal_gap 0.5)
				(thermal_bridge_width 0.5)
				(island_removal_mode 0)
			)
			(polygon
				(pts
					(arc
						(start 110.025434 -90.799666)
						(mid 105.000044 -85.774276)
						(end 99.974654 -90.799666)
					)
					(arc
						(start 99.492054 -90.799666)
						(mid 105.000044 -85.291676)
						(end 110.508034 -90.799666)
					)
				)
			)
		)
	)
	(footprint ""
		(layer "F.Cu")
		(at 157.302708 -161.19856 90)
		(property "Reference" "R572"
			(at -7.89432 19.359118 90)
			(unlocked yes)
			(layer "F.SilkS")
			(effects
				(font
					(size 0.7874 0.5842)
					(thickness 0.1524)
				)
				(justify left)
			)
		)
		(property "Value" ""
			(at 0 0 90)
			(layer "F.Fab")
			(effects
				(font
					(size 1.27 1.27)
				)
			)
		)
		(duplicate_pad_numbers_are_jumpers no)
		(fp_line
			(start 0.7874 -0.4064)
			(end 0.7874 0.4064)
			(stroke
				(width 0.1524)
				(type default)
			)
			(layer "F.SilkS")
		)
		(fp_line
			(start -0.7874 -0.4064)
			(end 0.7874 -0.4064)
			(stroke
				(width 0.1524)
				(type default)
			)
			(layer "F.SilkS")
		)
		(fp_line
			(start 0.7874 0.4064)
			(end -0.7874 0.4064)
			(stroke
				(width 0.1524)
				(type default)
			)
			(layer "F.SilkS")
		)
		(fp_line
			(start -0.7874 0.4064)
			(end -0.7874 -0.4064)
			(stroke
				(width 0.1524)
				(type default)
			)
			(layer "F.SilkS")
		)
		(fp_poly
			(pts
				(xy -0.508 0.2794) (xy -0.508 0.2286) (xy -0.635 0.2286) (xy -0.635 -0.254) (xy -0.5334 -0.254)
				(xy -0.5334 -0.2794) (xy 0.5334 -0.2794) (xy 0.5334 -0.254) (xy 0.635 -0.254) (xy 0.635 0.254) (xy 0.5334 0.254)
				(xy 0.5334 0.2794)
			)
			(stroke
				(width 0)
				(type default)
			)
			(fill no)
			(layer "F.CrtYd")
		)
		(pad "1" smd rect
			(at 0.40005 0 90)
			(size 0.4572 0.508)
			(layers "F.Cu" "F.Mask" "F.Paste")
			(net "P3V3_NODE1")
		)
		(pad "2" smd rect
			(at -0.40005 0 90)
			(size 0.4572 0.508)
			(layers "F.Cu" "F.Mask" "F.Paste")
			(net "SPI_LAN2_NVM_CS_N")
		)
	)
	(footprint ""
		(layer "F.Cu")
		(at 158.48076 -185.205624 -90)
		(property "Reference" "R821"
			(at -4.768088 -0.297942 90)
			(unlocked yes)
			(layer "F.SilkS")
			(effects
				(font
					(size 0.7874 0.5842)
					(thickness 0.1524)
				)
				(justify left)
			)
		)
		(property "Value" ""
			(at 0 0 270)
			(layer "F.Fab")
			(effects
				(font
					(size 1.27 1.27)
				)
			)
		)
		(duplicate_pad_numbers_are_jumpers no)
		(fp_line
			(start -0.7874 0.4064)
			(end -0.7874 -0.4064)
			(stroke
				(width 0.1524)
				(type default)
			)
			(layer "F.SilkS")
		)
		(fp_line
			(start 0.7874 0.4064)
			(end -0.7874 0.4064)
			(stroke
				(width 0.1524)
				(type default)
			)
			(layer "F.SilkS")
		)
		(fp_line
			(start -0.7874 -0.4064)
			(end 0.7874 -0.4064)
			(stroke
				(width 0.1524)
				(type default)
			)
			(layer "F.SilkS")
		)
		(fp_line
			(start 0.7874 -0.4064)
			(end 0.7874 0.4064)
			(stroke
				(width 0.1524)
				(type default)
			)
			(layer "F.SilkS")
		)
		(fp_poly
			(pts
				(xy -0.508 0.2794) (xy -0.508 0.2286) (xy -0.635 0.2286) (xy -0.635 -0.254) (xy -0.5334 -0.254)
				(xy -0.5334 -0.2794) (xy 0.5334 -0.2794) (xy 0.5334 -0.254) (xy 0.635 -0.254) (xy 0.635 0.254) (xy 0.5334 0.254)
				(xy 0.5334 0.2794)
			)
			(stroke
				(width 0)
				(type default)
			)
			(fill no)
			(layer "F.CrtYd")
		)
		(pad "1" smd rect
			(at 0.40005 0 270)
			(size 0.4572 0.508)
			(layers "F.Cu" "F.Mask" "F.Paste")
			(net "FAN1_TACH")
		)
		(pad "2" smd rect
			(at -0.40005 0 270)
			(size 0.4572 0.508)
			(layers "F.Cu" "F.Mask" "F.Paste")
			(net "FAN1_TACH_R")
		)
	)
	(footprint ""
		(layer "F.Cu")
		(at 135.74776 -188.126624 -90)
		(property "Reference" "R980"
			(at -4.949444 1.336548 90)
			(unlocked yes)
			(layer "F.SilkS")
			(effects
				(font
					(size 0.7874 0.5842)
					(thickness 0.1524)
				)
				(justify left)
			)
		)
		(property "Value" ""
			(at 0 0 270)
			(layer "F.Fab")
			(effects
				(font
					(size 1.27 1.27)
				)
			)
		)
		(duplicate_pad_numbers_are_jumpers no)
		(fp_line
			(start -0.7874 0.4064)
			(end -0.7874 -0.4064)
			(stroke
				(width 0.1524)
				(type default)
			)
			(layer "F.SilkS")
		)
		(fp_line
			(start 0.7874 0.4064)
			(end -0.7874 0.4064)
			(stroke
				(width 0.1524)
				(type default)
			)
			(layer "F.SilkS")
		)
		(fp_line
			(start -0.7874 -0.4064)
			(end 0.7874 -0.4064)
			(stroke
				(width 0.1524)
				(type default)
			)
			(layer "F.SilkS")
		)
		(fp_line
			(start 0.7874 -0.4064)
			(end 0.7874 0.4064)
			(stroke
				(width 0.1524)
				(type default)
			)
			(layer "F.SilkS")
		)
		(fp_poly
			(pts
				(xy -0.508 0.2794) (xy -0.508 0.2286) (xy -0.635 0.2286) (xy -0.635 -0.254) (xy -0.5334 -0.254)
				(xy -0.5334 -0.2794) (xy 0.5334 -0.2794) (xy 0.5334 -0.254) (xy 0.635 -0.254) (xy 0.635 0.254) (xy 0.5334 0.254)
				(xy 0.5334 0.2794)
			)
			(stroke
				(width 0)
				(type default)
			)
			(fill no)
			(layer "F.CrtYd")
		)
		(pad "1" smd rect
			(at 0.40005 0 270)
			(size 0.4572 0.508)
			(layers "F.Cu" "F.Mask" "F.Paste")
			(net "UART_T10_NODE1_RXD")
		)
		(pad "2" smd rect
			(at -0.40005 0 270)
			(size 0.4572 0.508)
			(layers "F.Cu" "F.Mask" "F.Paste")
			(net "UART_T10_NODE1_RXD_R")
		)
	)
	(footprint ""
		(layer "F.Cu")
		(at 148.07184 -176.29632 180)
		(property "Reference" "R806"
			(at 1.07442 2.382012 0)
			(unlocked yes)
			(layer "F.SilkS")
			(effects
				(font
					(size 0.7874 0.5842)
					(thickness 0.1524)
				)
				(justify left)
			)
		)
		(property "Value" ""
			(at 0 0 180)
			(layer "F.Fab")
			(effects
				(font
					(size 1.27 1.27)
				)
			)
		)
		(duplicate_pad_numbers_are_jumpers no)
		(fp_line
			(start 0.7874 0.4064)
			(end -0.7874 0.4064)
			(stroke
				(width 0.1524)
				(type default)
			)
			(layer "F.SilkS")
		)
		(fp_line
			(start 0.7874 -0.4064)
			(end 0.7874 0.4064)
			(stroke
				(width 0.1524)
				(type default)
			)
			(layer "F.SilkS")
		)
		(fp_line
			(start -0.7874 0.4064)
			(end -0.7874 -0.4064)
			(stroke
				(width 0.1524)
				(type default)
			)
			(layer "F.SilkS")
		)
		(fp_line
			(start -0.7874 -0.4064)
			(end 0.7874 -0.4064)
			(stroke
				(width 0.1524)
				(type default)
			)
			(layer "F.SilkS")
		)
		(fp_poly
			(pts
				(xy -0.508 0.2794) (xy -0.508 0.2286) (xy -0.635 0.2286) (xy -0.635 -0.254) (xy -0.5334 -0.254)
				(xy -0.5334 -0.2794) (xy 0.5334 -0.2794) (xy 0.5334 -0.254) (xy 0.635 -0.254) (xy 0.635 0.254) (xy 0.5334 0.254)
				(xy 0.5334 0.2794)
			)
			(stroke
				(width 0)
				(type default)
			)
			(fill no)
			(layer "F.CrtYd")
		)
		(pad "1" smd rect
			(at 0.40005 0 180)
			(size 0.4572 0.508)
			(layers "F.Cu" "F.Mask" "F.Paste")
			(net "CPLD_UART_RI_P3_N")
		)
		(pad "2" smd rect
			(at -0.40005 0 180)
			(size 0.4572 0.508)
			(layers "F.Cu" "F.Mask" "F.Paste")
			(net "GND")
		)
	)
	(footprint ""
		(layer "F.Cu")
		(at 193.143378 -143.39951 180)
		(property "Reference" "C476"
			(at -3.859784 -0.138684 0)
			(unlocked yes)
			(layer "F.SilkS")
			(effects
				(font
					(size 0.7874 0.5842)
					(thickness 0.1524)
				)
			)
		)
		(property "Value" ""
			(at 0 0 180)
			(layer "F.Fab")
			(effects
				(font
					(size 1.27 1.27)
				)
			)
		)
		(duplicate_pad_numbers_are_jumpers no)
		(fp_line
			(start 1.2954 0.5842)
			(end -1.2954 0.5842)
			(stroke
				(width 0.1524)
				(type default)
			)
			(layer "F.SilkS")
		)
		(fp_line
			(start 1.2954 -0.5842)
			(end 1.2954 0.5842)
			(stroke
				(width 0.1524)
				(type default)
			)
			(layer "F.SilkS")
		)
		(fp_line
			(start 0 -0.5842)
			(end 0 0.5842)
			(stroke
				(width 0.1524)
				(type default)
			)
			(layer "F.SilkS")
		)
		(fp_line
			(start -1.2954 0.5842)
			(end -1.2954 -0.5842)
			(stroke
				(width 0.1524)
				(type default)
			)
			(layer "F.SilkS")
		)
		(fp_line
			(start -1.2954 -0.5842)
			(end 1.2954 -0.5842)
			(stroke
				(width 0.1524)
				(type default)
			)
			(layer "F.SilkS")
		)
		(fp_poly
			(pts
				(xy 0.8636 -0.4572) (xy 0.8636 -0.3556) (xy 1.143 -0.3556) (xy 1.143 0.3556) (xy 0.8636 0.3556)
				(xy 0.8636 0.4572) (xy -0.8636 0.4572) (xy -0.8636 0.3556) (xy -1.143 0.3556) (xy -1.143 -0.3556)
				(xy -0.8636 -0.3556) (xy -0.8636 -0.4572)
			)
			(stroke
				(width 0)
				(type default)
			)
			(fill no)
			(layer "F.CrtYd")
		)
		(fp_line
			(start 0.884936 0.504952)
			(end -0.884936 0.504952)
			(stroke
				(width 0.1)
				(type default)
			)
			(layer "F.Fab")
		)
		(fp_line
			(start 0.884936 -0.504952)
			(end 0.884936 0.504952)
			(stroke
				(width 0.1)
				(type default)
			)
			(layer "F.Fab")
		)
		(fp_line
			(start -0.884936 0.504952)
			(end -0.884936 -0.504952)
			(stroke
				(width 0.1)
				(type default)
			)
			(layer "F.Fab")
		)
		(fp_line
			(start -0.884936 -0.504952)
			(end 0.884936 -0.504952)
			(stroke
				(width 0.1)
				(type default)
			)
			(layer "F.Fab")
		)
		(pad "1" smd rect
			(at 0.7366 0 270)
			(size 0.7112 0.8128)
			(layers "F.Cu" "F.Mask" "F.Paste")
			(net "P1V9_LAN2")
		)
		(pad "2" smd rect
			(at -0.7366 0 270)
			(size 0.7112 0.8128)
			(layers "F.Cu" "F.Mask" "F.Paste")
			(net "GND")
		)
	)
)
